(kicad_pcb
	(version 20260206)
	(generator "pcbnew")
	(generator_version "10.0")
	(general
		(thickness 1.6)
		(legacy_teardrops no)
	)
	(paper "A4")
	(title_block
		(title "03242023_DA0F0TMBIJ0_F0T_Motherboard_J_brd_V01_OCP.brd")
		(comment 1 "Grand Teton / footprint 1793 of 6105 (U13), pads 1-101 of 101")
	)
	(layers
		(0 "F.Cu" signal "TOP")
		(4 "In1.Cu" signal "GND")
		(6 "In2.Cu" signal "IN1")
		(8 "In3.Cu" signal "GND1")
		(10 "In4.Cu" signal "IN2")
		(12 "In5.Cu" signal "GND2")
		(14 "In6.Cu" signal "IN3")
		(16 "In7.Cu" signal "GND3")
		(18 "In8.Cu" signal "VCC")
		(20 "In9.Cu" signal "VCC1")
		(22 "In10.Cu" signal "GND4")
		(24 "In11.Cu" signal "IN4")
		(26 "In12.Cu" signal "GND5")
		(28 "In13.Cu" signal "IN5")
		(30 "In14.Cu" signal "GND6")
		(32 "In15.Cu" signal "IN6")
		(34 "In16.Cu" signal "GND7")
		(2 "B.Cu" signal "BOTTOM")
		(9 "F.Adhes" user "F.Adhesive")
		(11 "B.Adhes" user "B.Adhesive")
		(13 "F.Paste" user "Package Geometry/Pastemask Top")
		(15 "B.Paste" user "Package Geometry/Pastemask Bottom")
		(5 "F.SilkS" user "Ref Des/Silkscreen Top")
		(7 "B.SilkS" user "Ref Des/Silkscreen Bottom")
		(1 "F.Mask" user "Board Geometry/Soldermask Top")
		(3 "B.Mask" user "Board Geometry/Soldermask Bottom")
		(17 "Dwgs.User" user "User.Drawings")
		(19 "Cmts.User" user "User.Comments")
		(21 "Eco1.User" user "User.Eco1")
		(23 "Eco2.User" user "User.Eco2")
		(25 "Edge.Cuts" user "Board Geometry/Outline")
		(27 "Margin" user)
		(31 "F.CrtYd" user "Package Geometry/Place Bound Top")
		(29 "B.CrtYd" user "Package Geometry/Place Bound Bottom")
		(35 "F.Fab" user "Ref Des/Assembly Top")
		(33 "B.Fab" user "Ref Des/Assembly Bottom")
	)
	(footprint ""
		(layer "F.Cu")
		(at 255.68275 -99.563174)
		(property "Reference" "U13"
			(at 3.232404 -8.016748 0)
			(unlocked yes)
			(layer "F.SilkS")
			(effects
				(font
					(size 0.7874 0.5842)
					(thickness 0.1524)
				)
				(justify left)
			)
		)
		(property "Value" ""
			(at 0 0 0)
			(layer "F.Fab")
			(effects
				(font
					(size 1.27 1.27)
				)
			)
		)
		(duplicate_pad_numbers_are_jumpers no)
		(pad "A1" smd rect
			(at -3.875024 -3.24993 90)
			(size 0.1778 0.5588)
			(layers "F.Cu" "F.Mask" "F.Paste")
			(net "FM_CK440Q_DEV_25M_EN")
		)
		(pad "A2" smd rect
			(at -3.875024 -2.750058 90)
			(size 0.1778 0.5588)
			(layers "F.Cu" "F.Mask" "F.Paste")
			(net "CLK_25M_CK440_CPU1_DN")
		)
		(pad "A3" smd rect
			(at -3.875024 -2.249932 90)
			(size 0.1778 0.5588)
			(layers "F.Cu" "F.Mask" "F.Paste")
			(net "CLK_25M_CK440_CPU1_DP")
		)
		(pad "A4" smd rect
			(at -3.875024 -1.75006 90)
			(size 0.1778 0.5588)
			(layers "F.Cu" "F.Mask" "F.Paste")
			(net "CLK_25M_CK440_CPU0_DN")
		)
		(pad "A5" smd rect
			(at -3.875024 -1.249934 90)
			(size 0.1778 0.5588)
			(layers "F.Cu" "F.Mask" "F.Paste")
			(net "CLK_25M_CK440_CPU0_DP")
		)
		(pad "A6" smd rect
			(at -3.875024 -0.750062 90)
			(size 0.1778 0.5588)
			(layers "F.Cu" "F.Mask" "F.Paste")
			(net "TP_CLK_CK440_PFT_OUT_DP")
		)
		(pad "A7" smd rect
			(at -3.875024 -0.249936 90)
			(size 0.1778 0.5588)
			(layers "F.Cu" "F.Mask" "F.Paste")
			(net "TP_CLK_CK440_PFT_OUT_DN")
		)
		(pad "A8" smd rect
			(at -3.875024 0.249936 90)
			(size 0.1778 0.5588)
			(layers "F.Cu" "F.Mask" "F.Paste")
			(net "TP_CLK_PFT_IN_DP")
		)
		(pad "A9" smd rect
			(at -3.875024 0.750062 90)
			(size 0.1778 0.5588)
			(layers "F.Cu" "F.Mask" "F.Paste")
			(net "TP_CLK_PFT_IN_DN")
		)
		(pad "A10" smd rect
			(at -3.875024 1.249934 90)
			(size 0.1778 0.5588)
			(layers "F.Cu" "F.Mask" "F.Paste")
			(net "SMB_HOST_CLK_3V3AUX_SCL")
		)
		(pad "A11" smd rect
			(at -3.875024 1.75006 90)
			(size 0.1778 0.5588)
			(layers "F.Cu" "F.Mask" "F.Paste")
			(net "CLK_CK440_SMB_ADDR0")
		)
		(pad "A12" smd rect
			(at -3.875024 2.249932 90)
			(size 0.1778 0.5588)
			(layers "F.Cu" "F.Mask" "F.Paste")
			(net "P3V3_AUX_CLK_GEN_VDDXTAL_CK440")
		)
		(pad "A13" smd rect
			(at -3.875024 2.750058 90)
			(size 0.1778 0.5588)
			(layers "F.Cu" "F.Mask" "F.Paste")
			(net "XTAL_CLK_GEN1_25M_X1")
		)
		(pad "A14" smd rect
			(at -3.875024 3.24993 90)
			(size 0.1778 0.5588)
			(layers "F.Cu" "F.Mask" "F.Paste")
			(net "GND")
		)
		(pad "A15" smd rect
			(at -3.24993 3.875024)
			(size 0.1778 0.5588)
			(layers "F.Cu" "F.Mask" "F.Paste")
			(net "NC_CK440_A15")
		)
		(pad "A16" smd rect
			(at -2.750058 3.875024)
			(size 0.1778 0.5588)
			(layers "F.Cu" "F.Mask" "F.Paste")
			(net "FM_CLK_CK440_SS_EN")
		)
		(pad "A17" smd rect
			(at -2.249932 3.875024)
			(size 0.1778 0.5588)
			(layers "F.Cu" "F.Mask" "F.Paste")
			(net "FM_PLD_CLKS_DEV_EN")
		)
		(pad "A18" smd rect
			(at -1.75006 3.875024)
			(size 0.1778 0.5588)
			(layers "F.Cu" "F.Mask" "F.Paste")
			(net "NC_CLK_CK440_100M6_DN")
		)
		(pad "A19" smd rect
			(at -1.249934 3.875024)
			(size 0.1778 0.5588)
			(layers "F.Cu" "F.Mask" "F.Paste")
			(net "NC_CLK_CK440_100M6_DP")
		)
		(pad "A20" smd rect
			(at -0.750062 3.875024)
			(size 0.1778 0.5588)
			(layers "F.Cu" "F.Mask" "F.Paste")
			(net "NC_CLK_CK440_100M5_DN")
		)
		(pad "A21" smd rect
			(at -0.249936 3.875024)
			(size 0.1778 0.5588)
			(layers "F.Cu" "F.Mask" "F.Paste")
			(net "NC_CLK_CK440_100M5_DP")
		)
		(pad "A22" smd rect
			(at 0.249936 3.875024)
			(size 0.1778 0.5588)
			(layers "F.Cu" "F.Mask" "F.Paste")
			(net "NC_CLK_CK440_100M4_DN")
		)
		(pad "A23" smd rect
			(at 0.750062 3.875024)
			(size 0.1778 0.5588)
			(layers "F.Cu" "F.Mask" "F.Paste")
			(net "NC_CLK_CK440_100M4_DP")
		)
		(pad "A24" smd rect
			(at 1.249934 3.875024)
			(size 0.1778 0.5588)
			(layers "F.Cu" "F.Mask" "F.Paste")
			(net "NC_CLK_CK440_100M3_DN")
		)
		(pad "A25" smd rect
			(at 1.75006 3.875024)
			(size 0.1778 0.5588)
			(layers "F.Cu" "F.Mask" "F.Paste")
			(net "NC_CLK_CK440_100M3_DP")
		)
		(pad "A26" smd rect
			(at 2.249932 3.875024)
			(size 0.1778 0.5588)
			(layers "F.Cu" "F.Mask" "F.Paste")
			(net "CK440Q_OE_3")
		)
		(pad "A27" smd rect
			(at 2.750058 3.875024)
			(size 0.1778 0.5588)
			(layers "F.Cu" "F.Mask" "F.Paste")
			(net "NC_CLK_CK440_100M2_DN")
		)
		(pad "A28" smd rect
			(at 3.24993 3.875024)
			(size 0.1778 0.5588)
			(layers "F.Cu" "F.Mask" "F.Paste")
			(net "NC_CLK_CK440_100M2_DP")
		)
		(pad "A29" smd rect
			(at 3.875024 3.24993 270)
			(size 0.1778 0.5588)
			(layers "F.Cu" "F.Mask" "F.Paste")
			(net "CK440Q_OE_2")
		)
		(pad "A30" smd rect
			(at 3.875024 2.750058 270)
			(size 0.1778 0.5588)
			(layers "F.Cu" "F.Mask" "F.Paste")
			(net "CK440Q_OE_1")
		)
		(pad "A31" smd rect
			(at 3.875024 2.249932 270)
			(size 0.1778 0.5588)
			(layers "F.Cu" "F.Mask" "F.Paste")
			(net "NC_CLK_CK440_100M1_DN")
		)
		(pad "A32" smd rect
			(at 3.875024 1.75006 270)
			(size 0.1778 0.5588)
			(layers "F.Cu" "F.Mask" "F.Paste")
			(net "NC_CLK_CK440_100M1_DP")
		)
		(pad "A33" smd rect
			(at 3.875024 1.249934 270)
			(size 0.1778 0.5588)
			(layers "F.Cu" "F.Mask" "F.Paste")
			(net "CLK_100M_DB2000_DN")
		)
		(pad "A34" smd rect
			(at 3.875024 0.750062 270)
			(size 0.1778 0.5588)
			(layers "F.Cu" "F.Mask" "F.Paste")
			(net "CLK_100M_DB2000_DP")
		)
		(pad "A35" smd rect
			(at 3.875024 0.249936 270)
			(size 0.1778 0.5588)
			(layers "F.Cu" "F.Mask" "F.Paste")
			(net "NC_CLK_CK440_MXCK8_DN")
		)
		(pad "A36" smd rect
			(at 3.875024 -0.249936 270)
			(size 0.1778 0.5588)
			(layers "F.Cu" "F.Mask" "F.Paste")
			(net "NC_CLK_CK440_MXCK8_DP")
		)
		(pad "A37" smd rect
			(at 3.875024 -0.750062 270)
			(size 0.1778 0.5588)
			(layers "F.Cu" "F.Mask" "F.Paste")
			(net "NC_CLK_CK440_MXCK7_DN")
		)
		(pad "A38" smd rect
			(at 3.875024 -1.249934 270)
			(size 0.1778 0.5588)
			(layers "F.Cu" "F.Mask" "F.Paste")
			(net "NC_CLK_CK440_MXCK7_DP")
		)
		(pad "A39" smd rect
			(at 3.875024 -1.75006 270)
			(size 0.1778 0.5588)
			(layers "F.Cu" "F.Mask" "F.Paste")
			(net "NC_CLK_CK440_MXCK6_DN")
		)
		(pad "A40" smd rect
			(at 3.875024 -2.249932 270)
			(size 0.1778 0.5588)
			(layers "F.Cu" "F.Mask" "F.Paste")
			(net "NC_CLK_CK440_MXCK6_DP")
		)
		(pad "A41" smd rect
			(at 3.875024 -2.750058 270)
			(size 0.1778 0.5588)
			(layers "F.Cu" "F.Mask" "F.Paste")
			(net "NC_CLK_CK440_MXCK5_DN")
		)
		(pad "A42" smd rect
			(at 3.875024 -3.24993 270)
			(size 0.1778 0.5588)
			(layers "F.Cu" "F.Mask" "F.Paste")
			(net "NC_CLK_CK440_MXCK5_DP")
		)
		(pad "A43" smd rect
			(at 3.24993 -3.875024)
			(size 0.1778 0.5588)
			(layers "F.Cu" "F.Mask" "F.Paste")
			(net "NC_CLK_CK440_MXCK4_DN")
		)
		(pad "A44" smd rect
			(at 2.750058 -3.875024)
			(size 0.1778 0.5588)
			(layers "F.Cu" "F.Mask" "F.Paste")
			(net "NC_CLK_CK440_MXCK4_DP")
		)
		(pad "A45" smd rect
			(at 2.249932 -3.875024)
			(size 0.1778 0.5588)
			(layers "F.Cu" "F.Mask" "F.Paste")
			(net "NC_CLK_CK440_MXCK3_DN")
		)
		(pad "A46" smd rect
			(at 1.75006 -3.875024)
			(size 0.1778 0.5588)
			(layers "F.Cu" "F.Mask" "F.Paste")
			(net "NC_CLK_CK440_MXCK3_DP")
		)
		(pad "A47" smd rect
			(at 1.249934 -3.875024)
			(size 0.1778 0.5588)
			(layers "F.Cu" "F.Mask" "F.Paste")
			(net "CLK_100M_CK440_PCH_EXTCLK_R_DN")
		)
		(pad "A48" smd rect
			(at 0.750062 -3.875024)
			(size 0.1778 0.5588)
			(layers "F.Cu" "F.Mask" "F.Paste")
			(net "CLK_100M_CK440_PCH_EXTCLK_R_DP")
		)
		(pad "A49" smd rect
			(at 0.249936 -3.875024)
			(size 0.1778 0.5588)
			(layers "F.Cu" "F.Mask" "F.Paste")
			(net "NC_CLK_CK440_MXCK1_DN")
		)
		(pad "A50" smd rect
			(at -0.249936 -3.875024)
			(size 0.1778 0.5588)
			(layers "F.Cu" "F.Mask" "F.Paste")
			(net "NC_CLK_CK440_MXCK1_DP")
		)
		(pad "A51" smd rect
			(at -0.750062 -3.875024)
			(size 0.1778 0.5588)
			(layers "F.Cu" "F.Mask" "F.Paste")
			(net "NC_CLK_CK440_MXCK0_DN")
		)
		(pad "A52" smd rect
			(at -1.249934 -3.875024)
			(size 0.1778 0.5588)
			(layers "F.Cu" "F.Mask" "F.Paste")
			(net "NC_CLK_CK440_MXCK0_DP")
		)
		(pad "A53" smd rect
			(at -1.75006 -3.875024)
			(size 0.1778 0.5588)
			(layers "F.Cu" "F.Mask" "F.Paste")
			(net "TP_CK440_SBI_DATA_OUT")
		)
		(pad "A54" smd rect
			(at -2.249932 -3.875024)
			(size 0.1778 0.5588)
			(layers "F.Cu" "F.Mask" "F.Paste")
			(net "PD_CK440_SBI_CLK")
		)
		(pad "A55" smd rect
			(at -2.750058 -3.875024)
			(size 0.1778 0.5588)
			(layers "F.Cu" "F.Mask" "F.Paste")
			(net "CLK_25M_CK440_ISCLK_REF_DN")
		)
		(pad "A56" smd rect
			(at -3.24993 -3.875024)
			(size 0.1778 0.5588)
			(layers "F.Cu" "F.Mask" "F.Paste")
			(net "CLK_25M_CK440_ISCLK_REF_DP")
		)
		(pad "B1" smd rect
			(at -3.124962 -2.500122 90)
			(size 0.2794 0.4572)
			(layers "F.Cu" "F.Mask" "F.Paste")
			(net "P3V3_AUX_CLK_GEN_VDDA25M_CK440")
		)
		(pad "B2" smd rect
			(at -3.124962 -1.999996 90)
			(size 0.2794 0.4572)
			(layers "F.Cu" "F.Mask" "F.Paste")
			(net "NC_CK440_B2")
		)
		(pad "B3" smd rect
			(at -3.124962 -1.500124 90)
			(size 0.2794 0.4572)
			(layers "F.Cu" "F.Mask" "F.Paste")
			(net "NC_CK440_B3")
		)
		(pad "B4" smd rect
			(at -3.124962 -0.999998 90)
			(size 0.2794 0.4572)
			(layers "F.Cu" "F.Mask" "F.Paste")
			(net "PU_CLK_PFT_LOST_N")
		)
		(pad "B5" smd rect
			(at -3.124962 -0.499872 90)
			(size 0.2794 0.4572)
			(layers "F.Cu" "F.Mask" "F.Paste")
			(net "NC_CK440_B5")
		)
		(pad "B6" smd rect
			(at -3.124962 0 90)
			(size 0.2794 0.4572)
			(layers "F.Cu" "F.Mask" "F.Paste")
			(net "P3V3_AUX_CLK_GEN_VDDPT_CK440")
		)
		(pad "B7" smd rect
			(at -3.124962 0.499872 90)
			(size 0.2794 0.4572)
			(layers "F.Cu" "F.Mask" "F.Paste")
			(net "NC_CK440_B7")
		)
		(pad "B8" smd rect
			(at -3.124962 0.999998 90)
			(size 0.2794 0.4572)
			(layers "F.Cu" "F.Mask" "F.Paste")
			(net "SMB_HOST_CLK_3V3AUX_SDA")
		)
		(pad "B9" smd rect
			(at -3.124962 1.500124 90)
			(size 0.2794 0.4572)
			(layers "F.Cu" "F.Mask" "F.Paste")
			(net "CLK_CK440_SMB_ADDR1")
		)
		(pad "B10" smd rect
			(at -3.124962 1.999996 90)
			(size 0.2794 0.4572)
			(layers "F.Cu" "F.Mask" "F.Paste")
			(net "GND")
		)
		(pad "B11" smd rect
			(at -3.124962 2.500122 90)
			(size 0.2794 0.4572)
			(layers "F.Cu" "F.Mask" "F.Paste")
			(net "XTAL_CLK_GEN1_25M_X2")
		)
		(pad "B12" smd rect
			(at -2.500122 3.124962)
			(size 0.2794 0.4572)
			(layers "F.Cu" "F.Mask" "F.Paste")
			(net "GND")
		)
		(pad "B13" smd rect
			(at -1.999996 3.124962)
			(size 0.2794 0.4572)
			(layers "F.Cu" "F.Mask" "F.Paste")
			(net "NC_CK440_B13")
		)
		(pad "B14" smd rect
			(at -1.500124 3.124962)
			(size 0.2794 0.4572)
			(layers "F.Cu" "F.Mask" "F.Paste")
			(net "CK440Q_OE_6")
		)
		(pad "B15" smd rect
			(at -0.999998 3.124962)
			(size 0.2794 0.4572)
			(layers "F.Cu" "F.Mask" "F.Paste")
			(net "CK440Q_OE_5")
		)
		(pad "B16" smd rect
			(at -0.499872 3.124962)
			(size 0.2794 0.4572)
			(layers "F.Cu" "F.Mask" "F.Paste")
			(net "NC_CK440_B16")
		)
		(pad "B17" smd rect
			(at 0 3.124962)
			(size 0.2794 0.4572)
			(layers "F.Cu" "F.Mask" "F.Paste")
			(net "P3V3_AUX_CLK_GEN_VDDA100M_CK440")
		)
		(pad "B18" smd rect
			(at 0.499872 3.124962)
			(size 0.2794 0.4572)
			(layers "F.Cu" "F.Mask" "F.Paste")
			(net "NC_CK440_B18")
		)
		(pad "B19" smd rect
			(at 0.999998 3.124962)
			(size 0.2794 0.4572)
			(layers "F.Cu" "F.Mask" "F.Paste")
			(net "CK440Q_OE_4")
		)
		(pad "B20" smd rect
			(at 1.500124 3.124962)
			(size 0.2794 0.4572)
			(layers "F.Cu" "F.Mask" "F.Paste")
			(net "NC_CK440_B20")
		)
		(pad "B21" smd rect
			(at 1.999996 3.124962)
			(size 0.2794 0.4572)
			(layers "F.Cu" "F.Mask" "F.Paste")
			(net "P3V3_AUX_CLK_GEN_VDD_CK440")
		)
		(pad "B22" smd rect
			(at 2.500122 3.124962)
			(size 0.2794 0.4572)
			(layers "F.Cu" "F.Mask" "F.Paste")
			(net "NC_CK440_B22")
		)
		(pad "B23" smd rect
			(at 3.124962 2.500122 270)
			(size 0.2794 0.4572)
			(layers "F.Cu" "F.Mask" "F.Paste")
			(net "P3V3_AUX_CLK_GEN_VDD_CK440")
		)
		(pad "B24" smd rect
			(at 3.124962 1.999996 270)
			(size 0.2794 0.4572)
			(layers "F.Cu" "F.Mask" "F.Paste")
			(net "NC_CK440_B24")
		)
		(pad "B25" smd rect
			(at 3.124962 1.500124 270)
			(size 0.2794 0.4572)
			(layers "F.Cu" "F.Mask" "F.Paste")
			(net "NC_CK440_B25")
		)
		(pad "B26" smd rect
			(at 3.124962 0.999998 270)
			(size 0.2794 0.4572)
			(layers "F.Cu" "F.Mask" "F.Paste")
			(net "NC_CK440_B26")
		)
		(pad "B27" smd rect
			(at 3.124962 0.499872 270)
			(size 0.2794 0.4572)
			(layers "F.Cu" "F.Mask" "F.Paste")
			(net "FM_CLK_GEN1_OE0_N")
		)
		(pad "B28" smd rect
			(at 3.124962 0 270)
			(size 0.2794 0.4572)
			(layers "F.Cu" "F.Mask" "F.Paste")
			(net "NC_CK440_B28")
		)
		(pad "B29" smd rect
			(at 3.124962 -0.499872 270)
			(size 0.2794 0.4572)
			(layers "F.Cu" "F.Mask" "F.Paste")
			(net "P3V3_AUX_CLK_GEN_VDDMXCK_CK440")
		)
		(pad "B30" smd rect
			(at 3.124962 -0.999998 270)
			(size 0.2794 0.4572)
			(layers "F.Cu" "F.Mask" "F.Paste")
			(net "NC_CK440_B30")
		)
		(pad "B31" smd rect
			(at 3.124962 -1.500124 270)
			(size 0.2794 0.4572)
			(layers "F.Cu" "F.Mask" "F.Paste")
			(net "NC_CK440_B31")
		)
		(pad "B32" smd rect
			(at 3.124962 -1.999996 270)
			(size 0.2794 0.4572)
			(layers "F.Cu" "F.Mask" "F.Paste")
			(net "P3V3_AUX_CLK_GEN_VDDMXCK_CK440")
		)
		(pad "B33" smd rect
			(at 3.124962 -2.500122 270)
			(size 0.2794 0.4572)
			(layers "F.Cu" "F.Mask" "F.Paste")
			(net "NC_CK440_B33")
		)
		(pad "B34" smd rect
			(at 2.500122 -3.124962)
			(size 0.2794 0.4572)
			(layers "F.Cu" "F.Mask" "F.Paste")
			(net "NC_CK440_B34")
		)
		(pad "B35" smd rect
			(at 1.999996 -3.124962)
			(size 0.2794 0.4572)
			(layers "F.Cu" "F.Mask" "F.Paste")
			(net "P3V3_AUX_CLK_GEN_VDDMXCK_CK440")
		)
		(pad "B36" smd rect
			(at 1.500124 -3.124962)
			(size 0.2794 0.4572)
			(layers "F.Cu" "F.Mask" "F.Paste")
			(net "NC_CK440_B36")
		)
		(pad "B37" smd rect
			(at 0.999998 -3.124962)
			(size 0.2794 0.4572)
			(layers "F.Cu" "F.Mask" "F.Paste")
			(net "NC_CK440_B37")
		)
		(pad "B38" smd rect
			(at 0.499872 -3.124962)
			(size 0.2794 0.4572)
			(layers "F.Cu" "F.Mask" "F.Paste")
			(net "FM_CK440_MXCK_25M_100M")
		)
		(pad "B39" smd rect
			(at 0 -3.124962)
			(size 0.2794 0.4572)
			(layers "F.Cu" "F.Mask" "F.Paste")
			(net "NC_CK440_B39")
		)
		(pad "B40" smd rect
			(at -0.499872 -3.124962)
			(size 0.2794 0.4572)
			(layers "F.Cu" "F.Mask" "F.Paste")
			(net "P3V3_AUX_CLK_GEN_VDDMXCK_CK440")
		)
		(pad "B41" smd rect
			(at -0.999998 -3.124962)
			(size 0.2794 0.4572)
			(layers "F.Cu" "F.Mask" "F.Paste")
			(net "NC_CK440_B41")
		)
		(pad "B42" smd rect
			(at -1.500124 -3.124962)
			(size 0.2794 0.4572)
			(layers "F.Cu" "F.Mask" "F.Paste")
			(net "PU_CK440_SHFT_LD_N")
		)
		(pad "B43" smd rect
			(at -1.999996 -3.124962)
			(size 0.2794 0.4572)
			(layers "F.Cu" "F.Mask" "F.Paste")
			(net "PD_CK440_SBI_DATA_IN")
		)
		(pad "B44" smd rect
			(at -2.500122 -3.124962)
			(size 0.2794 0.4572)
			(layers "F.Cu" "F.Mask" "F.Paste")
			(net "NC_CK440_B44")
		)
		(pad "C1" smd circle
			(at 0 0)
			(size 0 0)
			(layers "F.Cu" "F.Mask" "F.Paste")
			(net "GND")
		)
	)
)
